# T6G (Grand Teton) — schematic netlist excerpt (pin names and nets, part order shuffled) for the footprints in the layout excerpt that follows; sources: Cadence DE-HDL packaged netlist, KiCad conversion of 04192023_DAF0TMB3IC0_F0TG_MB_C_brd_V02_OCP.brd

C6121  Q_CAP  0.1UF 25V 10% X7R  pkg 0402  page 179 : A = P1V2_CPU0_USB2_DVDD12 ; B = GND
R460  Q_RES  33 5% CHIP  pkg 0402LF  page 29 : A = SPI_CPU0_CS1_N ; B = SPI_CPU0_R_CS1_N

(kicad_pcb
	(version 20260206)
	(generator "pcbnew")
	(generator_version "10.0")
	(general
		(thickness 1.6)
		(legacy_teardrops no)
	)
	(paper "A4")
	(title_block
		(title "04192023_DAF0TMB3IC0_F0TG_MB_C_brd_V02_OCP.brd")
		(comment 1 "Grand Teton / footprints 6895-6896 of 8354")
	)
	(layers
		(0 "F.Cu" signal "TOP")
		(4 "In1.Cu" signal "GND")
		(6 "In2.Cu" signal "IN1")
		(8 "In3.Cu" signal "GND1")
		(10 "In4.Cu" signal "IN2")
		(12 "In5.Cu" signal "GND2")
		(14 "In6.Cu" signal "IN3")
		(16 "In7.Cu" signal "GND3")
		(18 "In8.Cu" signal "VCC")
		(20 "In9.Cu" signal "VCC1")
		(22 "In10.Cu" signal "GND4")
		(24 "In11.Cu" signal "IN4")
		(26 "In12.Cu" signal "GND5")
		(28 "In13.Cu" signal "IN5")
		(30 "In14.Cu" signal "GND6")
		(32 "In15.Cu" signal "IN6")
		(34 "In16.Cu" signal "GND7")
		(2 "B.Cu" signal "BOTTOM")
		(9 "F.Adhes" user "F.Adhesive")
		(11 "B.Adhes" user "B.Adhesive")
		(13 "F.Paste" user "Package Geometry/Pastemask Top")
		(15 "B.Paste" user "Package Geometry/Pastemask Bottom")
		(5 "F.SilkS" user "Ref Des/Silkscreen Top")
		(7 "B.SilkS" user "Ref Des/Silkscreen Bottom")
		(1 "F.Mask" user "Board Geometry/Soldermask Top")
		(3 "B.Mask" user "Board Geometry/Soldermask Bottom")
		(17 "Dwgs.User" user "User.Drawings")
		(19 "Cmts.User" user "User.Comments")
		(21 "Eco1.User" user "User.Eco1")
		(23 "Eco2.User" user "User.Eco2")
		(25 "Edge.Cuts" user "Board Geometry/Outline")
		(27 "Margin" user)
		(31 "F.CrtYd" user "Package Geometry/Place Bound Top")
		(29 "B.CrtYd" user "Package Geometry/Place Bound Bottom")
		(35 "F.Fab" user "Ref Des/Assembly Top")
		(33 "B.Fab" user "Ref Des/Assembly Bottom")
	)
	(footprint ""
		(layer "B.Cu")
		(at 393.440158 -327.644252)
		(property "Reference" "R460"
			(at 0 0 0)
			(layer "B.SilkS")
			(hide yes)
			(effects
				(font
					(size 1.27 1.27)
				)
				(justify mirror)
			)
		)
		(property "Value" ""
			(at 0 0 0)
			(layer "B.Fab")
			(effects
				(font
					(size 1.27 1.27)
				)
				(justify mirror)
			)
		)
		(duplicate_pad_numbers_are_jumpers no)
		(fp_line
			(start -0.7874 -0.4064)
			(end -0.7874 0.4064)
			(stroke
				(width 0.1524)
				(type default)
			)
			(layer "B.SilkS")
		)
		(fp_line
			(start -0.7874 0.4064)
			(end 0.7874 0.4064)
			(stroke
				(width 0.1524)
				(type default)
			)
			(layer "B.SilkS")
		)
		(fp_line
			(start 0.7874 -0.4064)
			(end -0.7874 -0.4064)
			(stroke
				(width 0.1524)
				(type default)
			)
			(layer "B.SilkS")
		)
		(fp_line
			(start 0.7874 0.4064)
			(end 0.7874 -0.4064)
			(stroke
				(width 0.1524)
				(type default)
			)
			(layer "B.SilkS")
		)
		(fp_line
			(start -0.67945 -0.3048)
			(end -0.67945 0.3048)
			(stroke
				(width 0.1)
				(type default)
			)
			(layer "B.Fab")
		)
		(fp_line
			(start -0.67945 0.3048)
			(end -0.120396 0.3048)
			(stroke
				(width 0.1)
				(type default)
			)
			(layer "B.Fab")
		)
		(fp_line
			(start -0.12065 -0.3048)
			(end -0.67945 -0.3048)
			(stroke
				(width 0.1)
				(type default)
			)
			(layer "B.Fab")
		)
		(fp_line
			(start -0.12065 -0.2794)
			(end -0.12065 -0.3048)
			(stroke
				(width 0.1)
				(type default)
			)
			(layer "B.Fab")
		)
		(fp_line
			(start -0.120396 0.2794)
			(end 0.12065 0.2794)
			(stroke
				(width 0.1)
				(type default)
			)
			(layer "B.Fab")
		)
		(fp_line
			(start -0.120396 0.3048)
			(end -0.120396 0.2794)
			(stroke
				(width 0.1)
				(type default)
			)
			(layer "B.Fab")
		)
		(fp_line
			(start 0.12065 -0.305054)
			(end 0.12065 -0.2794)
			(stroke
				(width 0.1)
				(type default)
			)
			(layer "B.Fab")
		)
		(fp_line
			(start 0.12065 -0.2794)
			(end -0.12065 -0.2794)
			(stroke
				(width 0.1)
				(type default)
			)
			(layer "B.Fab")
		)
		(fp_line
			(start 0.12065 0.2794)
			(end 0.12065 0.3048)
			(stroke
				(width 0.1)
				(type default)
			)
			(layer "B.Fab")
		)
		(fp_line
			(start 0.12065 0.3048)
			(end 0.67945 0.3048)
			(stroke
				(width 0.1)
				(type default)
			)
			(layer "B.Fab")
		)
		(fp_line
			(start 0.67945 -0.305054)
			(end 0.12065 -0.305054)
			(stroke
				(width 0.1)
				(type default)
			)
			(layer "B.Fab")
		)
		(fp_line
			(start 0.67945 0.3048)
			(end 0.67945 -0.305054)
			(stroke
				(width 0.1)
				(type default)
			)
			(layer "B.Fab")
		)
		(pad "1" smd circle
			(at 0.40005 0 180)
			(size 0 0)
			(layers "B.Cu" "B.Mask" "B.Paste")
			(net "SPI_CPU0_CS1_N")
		)
		(pad "2" smd circle
			(at -0.40005 0 180)
			(size 0 0)
			(layers "B.Cu" "B.Mask" "B.Paste")
			(net "SPI_CPU0_R_CS1_N")
		)
	)
	(footprint ""
		(layer "B.Cu")
		(at 109.550454 -30.533086 180)
		(property "Reference" "C6121"
			(at 0 0 0)
			(layer "B.SilkS")
			(hide yes)
			(effects
				(font
					(size 1.27 1.27)
				)
				(justify mirror)
			)
		)
		(property "Value" ""
			(at 0 0 0)
			(layer "B.Fab")
			(effects
				(font
					(size 1.27 1.27)
				)
				(justify mirror)
			)
		)
		(duplicate_pad_numbers_are_jumpers no)
		(fp_line
			(start 0.7874 0.4064)
			(end 0.7874 -0.4064)
			(stroke
				(width 0.1524)
				(type default)
			)
			(layer "B.SilkS")
		)
		(fp_line
			(start 0.7874 -0.4064)
			(end -0.7874 -0.4064)
			(stroke
				(width 0.1524)
				(type default)
			)
			(layer "B.SilkS")
		)
		(fp_line
			(start -0.7874 0.4064)
			(end 0.7874 0.4064)
			(stroke
				(width 0.1524)
				(type default)
			)
			(layer "B.SilkS")
		)
		(fp_line
			(start -0.7874 -0.4064)
			(end -0.7874 0.4064)
			(stroke
				(width 0.1524)
				(type default)
			)
			(layer "B.SilkS")
		)
		(fp_line
			(start 0.67945 0.3048)
			(end 0.67945 -0.305054)
			(stroke
				(width 0.1)
				(type default)
			)
			(layer "B.Fab")
		)
		(fp_line
			(start 0.67945 -0.305054)
			(end 0.12065 -0.305054)
			(stroke
				(width 0.1)
				(type default)
			)
			(layer "B.Fab")
		)
		(fp_line
			(start 0.12065 0.3048)
			(end 0.67945 0.3048)
			(stroke
				(width 0.1)
				(type default)
			)
			(layer "B.Fab")
		)
		(fp_line
			(start 0.12065 0.2794)
			(end 0.12065 0.3048)
			(stroke
				(width 0.1)
				(type default)
			)
			(layer "B.Fab")
		)
		(fp_line
			(start 0.12065 -0.2794)
			(end -0.12065 -0.2794)
			(stroke
				(width 0.1)
				(type default)
			)
			(layer "B.Fab")
		)
		(fp_line
			(start 0.12065 -0.305054)
			(end 0.12065 -0.2794)
			(stroke
				(width 0.1)
				(type default)
			)
			(layer "B.Fab")
		)
		(fp_line
			(start -0.120396 0.3048)
			(end -0.120396 0.2794)
			(stroke
				(width 0.1)
				(type default)
			)
			(layer "B.Fab")
		)
		(fp_line
			(start -0.120396 0.2794)
			(end 0.12065 0.2794)
			(stroke
				(width 0.1)
				(type default)
			)
			(layer "B.Fab")
		)
		(fp_line
			(start -0.12065 -0.2794)
			(end -0.12065 -0.3048)
			(stroke
				(width 0.1)
				(type default)
			)
			(layer "B.Fab")
		)
		(fp_line
			(start -0.12065 -0.3048)
			(end -0.67945 -0.3048)
			(stroke
				(width 0.1)
				(type default)
			)
			(layer "B.Fab")
		)
		(fp_line
			(start -0.67945 0.3048)
			(end -0.120396 0.3048)
			(stroke
				(width 0.1)
				(type default)
			)
			(layer "B.Fab")
		)
		(fp_line
			(start -0.67945 -0.3048)
			(end -0.67945 0.3048)
			(stroke
				(width 0.1)
				(type default)
			)
			(layer "B.Fab")
		)
		(pad "1" smd circle
			(at 0.40005 0)
			(size 0 0)
			(layers "B.Cu" "B.Mask" "B.Paste")
			(net "P1V2_CPU0_USB2_DVDD12")
		)
		(pad "2" smd circle
			(at -0.40005 0)
			(size 0 0)
			(layers "B.Cu" "B.Mask" "B.Paste")
			(net "GND")
		)
	)
)
